(kicad_pcb
	(version 20260206)
	(generator "pcbnew")
	(generator_version "10.0")
	(general
		(thickness 1.6)
		(legacy_teardrops no)
	)
	(paper "A4")
	(title_block
		(title "12092022_DA0F0TMDCD0_F0T_Management_Board_D_brd_V3_OCP.brd")
		(comment 1 "Grand Teton / footprints 225-230 of 1440")
	)
	(layers
		(0 "F.Cu" signal "TOP")
		(4 "In1.Cu" signal "GND")
		(6 "In2.Cu" signal "IN1")
		(8 "In3.Cu" signal "GND1")
		(10 "In4.Cu" signal "IN2")
		(12 "In5.Cu" signal "VCC")
		(14 "In6.Cu" signal "VCC1")
		(16 "In7.Cu" signal "IN3")
		(18 "In8.Cu" signal "GND2")
		(20 "In9.Cu" signal "IN4")
		(22 "In10.Cu" signal "GND3")
		(2 "B.Cu" signal "BOTTOM")
		(9 "F.Adhes" user "F.Adhesive")
		(11 "B.Adhes" user "B.Adhesive")
		(13 "F.Paste" user "Package Geometry/Pastemask Top")
		(15 "B.Paste" user "Package Geometry/Pastemask Bottom")
		(5 "F.SilkS" user "Ref Des/Silkscreen Top")
		(7 "B.SilkS" user "Ref Des/Silkscreen Bottom")
		(1 "F.Mask" user "Board Geometry/Soldermask Top")
		(3 "B.Mask" user "Board Geometry/Soldermask Bottom")
		(17 "Dwgs.User" user "User.Drawings")
		(19 "Cmts.User" user "User.Comments")
		(21 "Eco1.User" user "User.Eco1")
		(23 "Eco2.User" user "User.Eco2")
		(25 "Edge.Cuts" user "Board Geometry/Outline")
		(27 "Margin" user)
		(31 "F.CrtYd" user "Package Geometry/Place Bound Top")
		(29 "B.CrtYd" user "Package Geometry/Place Bound Bottom")
		(35 "F.Fab" user "Ref Des/Assembly Top")
		(33 "B.Fab" user "Ref Des/Assembly Bottom")
	)
	(footprint ""
		(layer "F.Cu")
		(at 38.608 -108.966 180)
		(property "Reference" "R63"
			(at 0 0 180)
			(layer "F.SilkS")
			(hide yes)
			(effects
				(font
					(size 1.27 1.27)
				)
			)
		)
		(property "Value" ""
			(at 0 0 180)
			(layer "F.Fab")
			(effects
				(font
					(size 1.27 1.27)
				)
			)
		)
		(duplicate_pad_numbers_are_jumpers no)
		(fp_line
			(start 0.7874 0.4064)
			(end -0.7874 0.4064)
			(stroke
				(width 0.1524)
				(type default)
			)
			(layer "F.SilkS")
		)
		(fp_line
			(start 0.7874 -0.4064)
			(end 0.7874 0.4064)
			(stroke
				(width 0.1524)
				(type default)
			)
			(layer "F.SilkS")
		)
		(fp_line
			(start -0.7874 0.4064)
			(end -0.7874 -0.4064)
			(stroke
				(width 0.1524)
				(type default)
			)
			(layer "F.SilkS")
		)
		(fp_line
			(start -0.7874 -0.4064)
			(end 0.7874 -0.4064)
			(stroke
				(width 0.1524)
				(type default)
			)
			(layer "F.SilkS")
		)
		(fp_line
			(start 0.67945 0.3048)
			(end 0.120396 0.3048)
			(stroke
				(width 0.1)
				(type default)
			)
			(layer "F.Fab")
		)
		(fp_line
			(start 0.67945 -0.3048)
			(end 0.67945 0.3048)
			(stroke
				(width 0.1)
				(type default)
			)
			(layer "F.Fab")
		)
		(fp_line
			(start 0.12065 -0.2794)
			(end 0.12065 -0.3048)
			(stroke
				(width 0.1)
				(type default)
			)
			(layer "F.Fab")
		)
		(fp_line
			(start 0.12065 -0.3048)
			(end 0.67945 -0.3048)
			(stroke
				(width 0.1)
				(type default)
			)
			(layer "F.Fab")
		)
		(fp_line
			(start 0.120396 0.3048)
			(end 0.120396 0.2794)
			(stroke
				(width 0.1)
				(type default)
			)
			(layer "F.Fab")
		)
		(fp_line
			(start 0.120396 0.2794)
			(end -0.12065 0.2794)
			(stroke
				(width 0.1)
				(type default)
			)
			(layer "F.Fab")
		)
		(fp_line
			(start -0.12065 0.3048)
			(end -0.67945 0.3048)
			(stroke
				(width 0.1)
				(type default)
			)
			(layer "F.Fab")
		)
		(fp_line
			(start -0.12065 0.2794)
			(end -0.12065 0.3048)
			(stroke
				(width 0.1)
				(type default)
			)
			(layer "F.Fab")
		)
		(fp_line
			(start -0.12065 -0.2794)
			(end 0.12065 -0.2794)
			(stroke
				(width 0.1)
				(type default)
			)
			(layer "F.Fab")
		)
		(fp_line
			(start -0.12065 -0.305054)
			(end -0.12065 -0.2794)
			(stroke
				(width 0.1)
				(type default)
			)
			(layer "F.Fab")
		)
		(fp_line
			(start -0.67945 0.3048)
			(end -0.67945 -0.305054)
			(stroke
				(width 0.1)
				(type default)
			)
			(layer "F.Fab")
		)
		(fp_line
			(start -0.67945 -0.305054)
			(end -0.12065 -0.305054)
			(stroke
				(width 0.1)
				(type default)
			)
			(layer "F.Fab")
		)
		(pad "1" smd circle
			(at -0.40005 0 180)
			(size 0 0)
			(layers "F.Cu" "F.Mask" "F.Paste")
			(net "SGPIO_CLK_1")
		)
		(pad "2" smd circle
			(at 0.40005 0 180)
			(size 0 0)
			(layers "F.Cu" "F.Mask" "F.Paste")
			(net "GND")
		)
	)
	(footprint ""
		(layer "F.Cu")
		(at 85.29955 -39.347394 180)
		(property "Reference" "R343"
			(at 0 0 180)
			(layer "F.SilkS")
			(hide yes)
			(effects
				(font
					(size 1.27 1.27)
				)
			)
		)
		(property "Value" ""
			(at 0 0 180)
			(layer "F.Fab")
			(effects
				(font
					(size 1.27 1.27)
				)
			)
		)
		(duplicate_pad_numbers_are_jumpers no)
		(fp_line
			(start 0.7874 0.4064)
			(end -0.7874 0.4064)
			(stroke
				(width 0.1524)
				(type default)
			)
			(layer "F.SilkS")
		)
		(fp_line
			(start 0.7874 -0.4064)
			(end 0.7874 0.4064)
			(stroke
				(width 0.1524)
				(type default)
			)
			(layer "F.SilkS")
		)
		(fp_line
			(start -0.7874 0.4064)
			(end -0.7874 -0.4064)
			(stroke
				(width 0.1524)
				(type default)
			)
			(layer "F.SilkS")
		)
		(fp_line
			(start -0.7874 -0.4064)
			(end 0.7874 -0.4064)
			(stroke
				(width 0.1524)
				(type default)
			)
			(layer "F.SilkS")
		)
		(fp_line
			(start 0.67945 0.3048)
			(end 0.120396 0.3048)
			(stroke
				(width 0.1)
				(type default)
			)
			(layer "F.Fab")
		)
		(fp_line
			(start 0.67945 -0.3048)
			(end 0.67945 0.3048)
			(stroke
				(width 0.1)
				(type default)
			)
			(layer "F.Fab")
		)
		(fp_line
			(start 0.12065 -0.2794)
			(end 0.12065 -0.3048)
			(stroke
				(width 0.1)
				(type default)
			)
			(layer "F.Fab")
		)
		(fp_line
			(start 0.12065 -0.3048)
			(end 0.67945 -0.3048)
			(stroke
				(width 0.1)
				(type default)
			)
			(layer "F.Fab")
		)
		(fp_line
			(start 0.120396 0.3048)
			(end 0.120396 0.2794)
			(stroke
				(width 0.1)
				(type default)
			)
			(layer "F.Fab")
		)
		(fp_line
			(start 0.120396 0.2794)
			(end -0.12065 0.2794)
			(stroke
				(width 0.1)
				(type default)
			)
			(layer "F.Fab")
		)
		(fp_line
			(start -0.12065 0.3048)
			(end -0.67945 0.3048)
			(stroke
				(width 0.1)
				(type default)
			)
			(layer "F.Fab")
		)
		(fp_line
			(start -0.12065 0.2794)
			(end -0.12065 0.3048)
			(stroke
				(width 0.1)
				(type default)
			)
			(layer "F.Fab")
		)
		(fp_line
			(start -0.12065 -0.2794)
			(end 0.12065 -0.2794)
			(stroke
				(width 0.1)
				(type default)
			)
			(layer "F.Fab")
		)
		(fp_line
			(start -0.12065 -0.305054)
			(end -0.12065 -0.2794)
			(stroke
				(width 0.1)
				(type default)
			)
			(layer "F.Fab")
		)
		(fp_line
			(start -0.67945 0.3048)
			(end -0.67945 -0.305054)
			(stroke
				(width 0.1)
				(type default)
			)
			(layer "F.Fab")
		)
		(fp_line
			(start -0.67945 -0.305054)
			(end -0.12065 -0.305054)
			(stroke
				(width 0.1)
				(type default)
			)
			(layer "F.Fab")
		)
		(pad "1" smd circle
			(at -0.40005 0 180)
			(size 0 0)
			(layers "F.Cu" "F.Mask" "F.Paste")
			(net "GND")
		)
		(pad "2" smd circle
			(at 0.40005 0 180)
			(size 0 0)
			(layers "F.Cu" "F.Mask" "F.Paste")
			(net "M_BMC_DDR4_MCS_N")
		)
	)
	(footprint ""
		(layer "F.Cu")
		(at 69.097398 -62.725808 -90)
		(property "Reference" "C80"
			(at 0 0 270)
			(layer "F.SilkS")
			(hide yes)
			(effects
				(font
					(size 1.27 1.27)
				)
			)
		)
		(property "Value" ""
			(at 0 0 270)
			(layer "F.Fab")
			(effects
				(font
					(size 1.27 1.27)
				)
			)
		)
		(duplicate_pad_numbers_are_jumpers no)
		(fp_line
			(start -0.7874 0.4064)
			(end -0.7874 -0.4064)
			(stroke
				(width 0.1524)
				(type default)
			)
			(layer "F.SilkS")
		)
		(fp_line
			(start 0.7874 0.4064)
			(end -0.7874 0.4064)
			(stroke
				(width 0.1524)
				(type default)
			)
			(layer "F.SilkS")
		)
		(fp_line
			(start -0.7874 -0.4064)
			(end 0.7874 -0.4064)
			(stroke
				(width 0.1524)
				(type default)
			)
			(layer "F.SilkS")
		)
		(fp_line
			(start 0.7874 -0.4064)
			(end 0.7874 0.4064)
			(stroke
				(width 0.1524)
				(type default)
			)
			(layer "F.SilkS")
		)
		(fp_line
			(start -0.67945 0.3048)
			(end -0.67945 -0.305054)
			(stroke
				(width 0.1)
				(type default)
			)
			(layer "F.Fab")
		)
		(fp_line
			(start -0.12065 0.3048)
			(end -0.67945 0.3048)
			(stroke
				(width 0.1)
				(type default)
			)
			(layer "F.Fab")
		)
		(fp_line
			(start 0.120396 0.3048)
			(end 0.120396 0.2794)
			(stroke
				(width 0.1)
				(type default)
			)
			(layer "F.Fab")
		)
		(fp_line
			(start 0.67945 0.3048)
			(end 0.120396 0.3048)
			(stroke
				(width 0.1)
				(type default)
			)
			(layer "F.Fab")
		)
		(fp_line
			(start -0.12065 0.2794)
			(end -0.12065 0.3048)
			(stroke
				(width 0.1)
				(type default)
			)
			(layer "F.Fab")
		)
		(fp_line
			(start 0.120396 0.2794)
			(end -0.12065 0.2794)
			(stroke
				(width 0.1)
				(type default)
			)
			(layer "F.Fab")
		)
		(fp_line
			(start -0.12065 -0.2794)
			(end 0.12065 -0.2794)
			(stroke
				(width 0.1)
				(type default)
			)
			(layer "F.Fab")
		)
		(fp_line
			(start 0.12065 -0.2794)
			(end 0.12065 -0.3048)
			(stroke
				(width 0.1)
				(type default)
			)
			(layer "F.Fab")
		)
		(fp_line
			(start 0.12065 -0.3048)
			(end 0.67945 -0.3048)
			(stroke
				(width 0.1)
				(type default)
			)
			(layer "F.Fab")
		)
		(fp_line
			(start 0.67945 -0.3048)
			(end 0.67945 0.3048)
			(stroke
				(width 0.1)
				(type default)
			)
			(layer "F.Fab")
		)
		(fp_line
			(start -0.67945 -0.305054)
			(end -0.12065 -0.305054)
			(stroke
				(width 0.1)
				(type default)
			)
			(layer "F.Fab")
		)
		(fp_line
			(start -0.12065 -0.305054)
			(end -0.12065 -0.2794)
			(stroke
				(width 0.1)
				(type default)
			)
			(layer "F.Fab")
		)
		(pad "1" smd circle
			(at -0.40005 0 270)
			(size 0 0)
			(layers "F.Cu" "F.Mask" "F.Paste")
			(net "P1V8_STBY_RC_VCC18A")
		)
		(pad "2" smd circle
			(at 0.40005 0 270)
			(size 0 0)
			(layers "F.Cu" "F.Mask" "F.Paste")
			(net "GND")
		)
	)
	(footprint ""
		(layer "F.Cu")
		(at 45.085 -83.6168)
		(property "Reference" "R559"
			(at 0 0 0)
			(layer "F.SilkS")
			(hide yes)
			(effects
				(font
					(size 1.27 1.27)
				)
			)
		)
		(property "Value" ""
			(at 0 0 0)
			(layer "F.Fab")
			(effects
				(font
					(size 1.27 1.27)
				)
			)
		)
		(duplicate_pad_numbers_are_jumpers no)
		(fp_line
			(start -0.7874 -0.4064)
			(end 0.7874 -0.4064)
			(stroke
				(width 0.1524)
				(type default)
			)
			(layer "F.SilkS")
		)
		(fp_line
			(start -0.7874 0.4064)
			(end -0.7874 -0.4064)
			(stroke
				(width 0.1524)
				(type default)
			)
			(layer "F.SilkS")
		)
		(fp_line
			(start 0.7874 -0.4064)
			(end 0.7874 0.4064)
			(stroke
				(width 0.1524)
				(type default)
			)
			(layer "F.SilkS")
		)
		(fp_line
			(start 0.7874 0.4064)
			(end -0.7874 0.4064)
			(stroke
				(width 0.1524)
				(type default)
			)
			(layer "F.SilkS")
		)
		(fp_line
			(start -0.67945 -0.305054)
			(end -0.12065 -0.305054)
			(stroke
				(width 0.1)
				(type default)
			)
			(layer "F.Fab")
		)
		(fp_line
			(start -0.67945 0.3048)
			(end -0.67945 -0.305054)
			(stroke
				(width 0.1)
				(type default)
			)
			(layer "F.Fab")
		)
		(fp_line
			(start -0.12065 -0.305054)
			(end -0.12065 -0.2794)
			(stroke
				(width 0.1)
				(type default)
			)
			(layer "F.Fab")
		)
		(fp_line
			(start -0.12065 -0.2794)
			(end 0.12065 -0.2794)
			(stroke
				(width 0.1)
				(type default)
			)
			(layer "F.Fab")
		)
		(fp_line
			(start -0.12065 0.2794)
			(end -0.12065 0.3048)
			(stroke
				(width 0.1)
				(type default)
			)
			(layer "F.Fab")
		)
		(fp_line
			(start -0.12065 0.3048)
			(end -0.67945 0.3048)
			(stroke
				(width 0.1)
				(type default)
			)
			(layer "F.Fab")
		)
		(fp_line
			(start 0.120396 0.2794)
			(end -0.12065 0.2794)
			(stroke
				(width 0.1)
				(type default)
			)
			(layer "F.Fab")
		)
		(fp_line
			(start 0.120396 0.3048)
			(end 0.120396 0.2794)
			(stroke
				(width 0.1)
				(type default)
			)
			(layer "F.Fab")
		)
		(fp_line
			(start 0.12065 -0.3048)
			(end 0.67945 -0.3048)
			(stroke
				(width 0.1)
				(type default)
			)
			(layer "F.Fab")
		)
		(fp_line
			(start 0.12065 -0.2794)
			(end 0.12065 -0.3048)
			(stroke
				(width 0.1)
				(type default)
			)
			(layer "F.Fab")
		)
		(fp_line
			(start 0.67945 -0.3048)
			(end 0.67945 0.3048)
			(stroke
				(width 0.1)
				(type default)
			)
			(layer "F.Fab")
		)
		(fp_line
			(start 0.67945 0.3048)
			(end 0.120396 0.3048)
			(stroke
				(width 0.1)
				(type default)
			)
			(layer "F.Fab")
		)
		(pad "1" smd circle
			(at -0.40005 0)
			(size 0 0)
			(layers "F.Cu" "F.Mask" "F.Paste")
			(net "SPI_BMC_BT_WP0_N_R")
		)
		(pad "2" smd circle
			(at 0.40005 0)
			(size 0 0)
			(layers "F.Cu" "F.Mask" "F.Paste")
			(net "FLASH_LATCH_Q_N_R2")
		)
	)
	(footprint ""
		(layer "F.Cu")
		(at 60.380118 -6.290056)
		(property "Reference" "D22"
			(at -1.143 -2.708148 0)
			(unlocked yes)
			(layer "F.SilkS")
			(effects
				(font
					(size 0.7874 0.5842)
					(thickness 0.1524)
				)
				(justify left)
			)
		)
		(property "Value" ""
			(at 0 0 0)
			(layer "F.Fab")
			(effects
				(font
					(size 1.27 1.27)
				)
			)
		)
		(duplicate_pad_numbers_are_jumpers no)
		(fp_line
			(start -1.080008 -1.999996)
			(end 3.620008 -1.999996)
			(stroke
				(width 0.1524)
				(type default)
			)
			(layer "F.SilkS")
		)
		(fp_line
			(start -1.080008 3.999992)
			(end -1.080008 -1.999996)
			(stroke
				(width 0.1524)
				(type default)
			)
			(layer "F.SilkS")
		)
		(fp_line
			(start -0.230124 3.999992)
			(end -1.080008 3.999992)
			(stroke
				(width 0.1524)
				(type default)
			)
			(layer "F.SilkS")
		)
		(fp_line
			(start -0.230124 5.199888)
			(end -0.230124 3.999992)
			(stroke
				(width 0.1524)
				(type default)
			)
			(layer "F.SilkS")
		)
		(fp_line
			(start 2.770124 3.999992)
			(end 2.770124 5.199888)
			(stroke
				(width 0.1524)
				(type default)
			)
			(layer "F.SilkS")
		)
		(fp_line
			(start 3.620008 -1.999996)
			(end 3.620008 3.999992)
			(stroke
				(width 0.1524)
				(type default)
			)
			(layer "F.SilkS")
		)
		(fp_line
			(start 3.620008 3.999992)
			(end 2.770124 3.999992)
			(stroke
				(width 0.1524)
				(type default)
			)
			(layer "F.SilkS")
		)
		(fp_arc
			(start 1.27 6.700012)
			(mid 0.209252 6.260636)
			(end -0.230124 5.199888)
			(stroke
				(width 0.1524)
				(type default)
			)
			(layer "F.SilkS")
		)
		(fp_arc
			(start 2.770124 5.199888)
			(mid 2.330748 6.260636)
			(end 1.27 6.700012)
			(stroke
				(width 0.1524)
				(type default)
			)
			(layer "F.SilkS")
		)
		(fp_line
			(start -1.080008 -1.999996)
			(end 3.620008 -1.999996)
			(stroke
				(width 0.1)
				(type default)
			)
			(layer "F.Fab")
		)
		(fp_line
			(start -1.080008 3.999992)
			(end -1.080008 -1.999996)
			(stroke
				(width 0.1)
				(type default)
			)
			(layer "F.Fab")
		)
		(fp_line
			(start -0.230124 3.999992)
			(end -1.080008 3.999992)
			(stroke
				(width 0.1)
				(type default)
			)
			(layer "F.Fab")
		)
		(fp_line
			(start -0.230124 5.199888)
			(end -0.230124 3.999992)
			(stroke
				(width 0.1)
				(type default)
			)
			(layer "F.Fab")
		)
		(fp_line
			(start 2.770124 3.999992)
			(end 2.770124 5.199888)
			(stroke
				(width 0.1)
				(type default)
			)
			(layer "F.Fab")
		)
		(fp_line
			(start 3.620008 -1.999996)
			(end 3.620008 3.999992)
			(stroke
				(width 0.1)
				(type default)
			)
			(layer "F.Fab")
		)
		(fp_line
			(start 3.620008 3.999992)
			(end 2.770124 3.999992)
			(stroke
				(width 0.1)
				(type default)
			)
			(layer "F.Fab")
		)
		(fp_arc
			(start 1.27 6.700012)
			(mid 0.209252 6.260636)
			(end -0.230124 5.199888)
			(stroke
				(width 0.1)
				(type default)
			)
			(layer "F.Fab")
		)
		(fp_arc
			(start 2.770124 5.199888)
			(mid 2.330748 6.260636)
			(end 1.27 6.700012)
			(stroke
				(width 0.1)
				(type default)
			)
			(layer "F.Fab")
		)
		(pad "A" thru_hole rect
			(at 0 0)
			(size 1.2192 1.2192)
			(drill 0.8128)
			(layers "*.Cu" "*.Mask")
			(remove_unused_layers no)
			(net "LED_D22_R")
			(clearance 0.0508)
			(thermal_gap 0.0508)
			(padstack
				(mode front_inner_back)
				(layer "Inner"
					(shape circle)
					(size 1.2192 1.2192)
					(clearance 0.0508)
				)
				(layer "B.Cu"
					(shape rect)
					(size 1.2192 1.2192)
					(clearance 0.0508)
				)
			)
		)
		(pad "C" thru_hole circle
			(at 2.54 0)
			(size 1.2192 1.2192)
			(drill 0.8128)
			(layers "*.Cu" "*.Mask")
			(remove_unused_layers no)
			(net "LED_D22_R1")
			(clearance 0.0508)
			(thermal_gap 0.0508)
		)
	)
	(footprint ""
		(layer "F.Cu")
		(at 47.752 -34.6456 -90)
		(property "Reference" "R132"
			(at 0 0 270)
			(layer "F.SilkS")
			(hide yes)
			(effects
				(font
					(size 1.27 1.27)
				)
			)
		)
		(property "Value" ""
			(at 0 0 270)
			(layer "F.Fab")
			(effects
				(font
					(size 1.27 1.27)
				)
			)
		)
		(duplicate_pad_numbers_are_jumpers no)
		(fp_line
			(start -0.7874 0.4064)
			(end -0.7874 -0.4064)
			(stroke
				(width 0.1524)
				(type default)
			)
			(layer "F.SilkS")
		)
		(fp_line
			(start 0.7874 0.4064)
			(end -0.7874 0.4064)
			(stroke
				(width 0.1524)
				(type default)
			)
			(layer "F.SilkS")
		)
		(fp_line
			(start -0.7874 -0.4064)
			(end 0.7874 -0.4064)
			(stroke
				(width 0.1524)
				(type default)
			)
			(layer "F.SilkS")
		)
		(fp_line
			(start 0.7874 -0.4064)
			(end 0.7874 0.4064)
			(stroke
				(width 0.1524)
				(type default)
			)
			(layer "F.SilkS")
		)
		(fp_line
			(start -0.67945 0.3048)
			(end -0.67945 -0.305054)
			(stroke
				(width 0.1)
				(type default)
			)
			(layer "F.Fab")
		)
		(fp_line
			(start -0.12065 0.3048)
			(end -0.67945 0.3048)
			(stroke
				(width 0.1)
				(type default)
			)
			(layer "F.Fab")
		)
		(fp_line
			(start 0.120396 0.3048)
			(end 0.120396 0.2794)
			(stroke
				(width 0.1)
				(type default)
			)
			(layer "F.Fab")
		)
		(fp_line
			(start 0.67945 0.3048)
			(end 0.120396 0.3048)
			(stroke
				(width 0.1)
				(type default)
			)
			(layer "F.Fab")
		)
		(fp_line
			(start -0.12065 0.2794)
			(end -0.12065 0.3048)
			(stroke
				(width 0.1)
				(type default)
			)
			(layer "F.Fab")
		)
		(fp_line
			(start 0.120396 0.2794)
			(end -0.12065 0.2794)
			(stroke
				(width 0.1)
				(type default)
			)
			(layer "F.Fab")
		)
		(fp_line
			(start -0.12065 -0.2794)
			(end 0.12065 -0.2794)
			(stroke
				(width 0.1)
				(type default)
			)
			(layer "F.Fab")
		)
		(fp_line
			(start 0.12065 -0.2794)
			(end 0.12065 -0.3048)
			(stroke
				(width 0.1)
				(type default)
			)
			(layer "F.Fab")
		)
		(fp_line
			(start 0.12065 -0.3048)
			(end 0.67945 -0.3048)
			(stroke
				(width 0.1)
				(type default)
			)
			(layer "F.Fab")
		)
		(fp_line
			(start 0.67945 -0.3048)
			(end 0.67945 0.3048)
			(stroke
				(width 0.1)
				(type default)
			)
			(layer "F.Fab")
		)
		(fp_line
			(start -0.67945 -0.305054)
			(end -0.12065 -0.305054)
			(stroke
				(width 0.1)
				(type default)
			)
			(layer "F.Fab")
		)
		(fp_line
			(start -0.12065 -0.305054)
			(end -0.12065 -0.2794)
			(stroke
				(width 0.1)
				(type default)
			)
			(layer "F.Fab")
		)
		(pad "1" smd circle
			(at -0.40005 0 270)
			(size 0 0)
			(layers "F.Cu" "F.Mask" "F.Paste")
			(net "SMB_BMC_MM1_R_SCL")
		)
		(pad "2" smd circle
			(at 0.40005 0 270)
			(size 0 0)
			(layers "F.Cu" "F.Mask" "F.Paste")
			(net "SMB_BMC_MM1_SCL")
		)
	)
)
